(kicad_pcb
	(version 20240108)
	(generator "pcbnew")
	(generator_version "8.0")
	(general
		(thickness 1.62)
		(legacy_teardrops no)
	)
	(paper "A4")
	(title_block
		(title "Jetson Orin Baseboard")
		(date "2025-03-12")
		(rev "1.3.4")
		(company "Antmicro Ltd")
		(comment 1 "www.antmicro.com")
		(comment 9 "footprints 254-258 of 677")
	)
	(layers
		(0 "F.Cu" signal)
		(1 "In1.Cu" signal)
		(2 "In2.Cu" signal)
		(3 "In3.Cu" signal)
		(4 "In4.Cu" jumper)
		(5 "In5.Cu" signal)
		(6 "In6.Cu" signal)
		(31 "B.Cu" signal)
		(32 "B.Adhes" user "B.Adhesive")
		(33 "F.Adhes" user "F.Adhesive")
		(34 "B.Paste" user)
		(35 "F.Paste" user)
		(36 "B.SilkS" user "B.Silkscreen")
		(37 "F.SilkS" user "F.Silkscreen")
		(38 "B.Mask" user)
		(39 "F.Mask" user)
		(40 "Dwgs.User" user "User.Drawings")
		(41 "Cmts.User" user "User.Comments")
		(42 "Eco1.User" user "User.Eco1")
		(43 "Eco2.User" user "User.Eco2")
		(44 "Edge.Cuts" user)
		(45 "Margin" user)
		(46 "B.CrtYd" user "B.Courtyard")
		(47 "F.CrtYd" user "F.Courtyard")
		(48 "B.Fab" user)
		(49 "F.Fab" user)
	)
	(footprint "antmicro-footprints:R_Array_4x0402"
		(layer "F.Cu")
		(at 147.85 106.14 -90)
		(property "Reference" "R102"
			(at 1.53 -1.6 -90)
			(layer "F.SilkS")
			(effects
				(font
					(size 0.7 0.7)
					(thickness 0.15)
				)
				(justify left bottom)
			)
		)
		(property "Value" "R_4x330R_0402_array"
			(at -1.5 2 -90)
			(layer "F.Fab")
			(effects
				(font
					(size 0.7 0.7)
					(thickness 0.15)
				)
				(justify left bottom)
			)
		)
		(property "Footprint" "antmicro-footprints:R_Array_4x0402"
			(at 0 0 -90)
			(layer "F.Fab")
			(hide yes)
			(effects
				(font
					(size 1.27 1.27)
					(thickness 0.15)
				)
			)
		)
		(property "Datasheet" "http://industrial.panasonic.com/cdbs/www-data/pdf/AOC0000/AOC0000C14.pdf"
			(at 0 0 -90)
			(layer "F.Fab")
			(hide yes)
			(effects
				(font
					(size 1.27 1.27)
					(thickness 0.15)
				)
			)
		)
		(property "Author" "Antmicro"
			(at 41.71 253.99 0)
			(layer "F.Fab")
			(hide yes)
			(effects
				(font
					(size 1 1)
					(thickness 0.15)
				)
			)
		)
		(property "License" "Apache-2.0"
			(at 41.71 253.99 0)
			(layer "F.Fab")
			(hide yes)
			(effects
				(font
					(size 1 1)
					(thickness 0.15)
				)
			)
		)
		(property "MPN" "EXB-28V331JX"
			(at 41.71 253.99 0)
			(layer "F.Fab")
			(hide yes)
			(effects
				(font
					(size 1 1)
					(thickness 0.15)
				)
			)
		)
		(property "Manufacturer" "Panasonic"
			(at 41.71 253.99 0)
			(layer "F.Fab")
			(hide yes)
			(effects
				(font
					(size 1 1)
					(thickness 0.15)
				)
			)
		)
		(property "Val" "R_4x330R_0402"
			(at 41.71 253.99 0)
			(layer "F.Fab")
			(hide yes)
			(effects
				(font
					(size 1 1)
					(thickness 0.15)
				)
			)
		)
		(sheetname "Peripherals")
		(sheetfile "peripherals.kicad_sch")
		(attr smd)
		(fp_line
			(start 1.167 0.498)
			(end 1.167 -0.5)
			(stroke
				(width 0.15)
				(type solid)
			)
			(layer "F.SilkS")
		)
		(fp_line
			(start -1.17 -0.5)
			(end -1.17 0.498)
			(stroke
				(width 0.15)
				(type solid)
			)
			(layer "F.SilkS")
		)
		(fp_rect
			(start -1.2 -0.9)
			(end 1.2 0.9)
			(stroke
				(width 0.05)
				(type solid)
			)
			(fill none)
			(layer "F.CrtYd")
		)
		(fp_line
			(start -1 0.498)
			(end -1 -0.5)
			(stroke
				(width 0.15)
				(type solid)
			)
			(layer "F.Fab")
		)
		(fp_line
			(start 0.998 0.498)
			(end -1 0.498)
			(stroke
				(width 0.15)
				(type solid)
			)
			(layer "F.Fab")
		)
		(fp_line
			(start -1 -0.5)
			(end 0.998 -0.5)
			(stroke
				(width 0.15)
				(type solid)
			)
			(layer "F.Fab")
		)
		(fp_line
			(start 0.998 -0.5)
			(end 0.998 0.498)
			(stroke
				(width 0.15)
				(type solid)
			)
			(layer "F.Fab")
		)
		(fp_text user "Author: Antmicro"
			(at -1.5 4.5 -90)
			(layer "F.Fab")
			(hide yes)
			(effects
				(font
					(size 0.7 0.7)
					(thickness 0.15)
				)
				(justify left bottom)
			)
		)
		(fp_text user "${REFERENCE}"
			(at -1.5 3.25 -90)
			(layer "F.Fab")
			(hide yes)
			(effects
				(font
					(size 0.7 0.7)
					(thickness 0.15)
				)
				(justify left bottom)
			)
		)
		(fp_text user "License: Apache-2.0"
			(at -1.5 5.75 -90)
			(layer "F.Fab")
			(hide yes)
			(effects
				(font
					(size 0.7 0.7)
					(thickness 0.15)
				)
				(justify left bottom)
			)
		)
		(pad "1" smd roundrect
			(at -0.802 0.45 270)
			(size 0.4 0.5)
			(layers "F.Cu" "F.Paste" "F.Mask")
			(roundrect_rratio 0.25)
			(net 674 "unconnected-(R102-R1.1-Pad1)")
			(pinfunction "R1.1")
			(pintype "passive+no_connect")
		)
		(pad "2" smd roundrect
			(at -0.272 0.45 270)
			(size 0.4 0.5)
			(layers "F.Cu" "F.Paste" "F.Mask")
			(roundrect_rratio 0.25)
			(net 675 "unconnected-(R102-R2.1-Pad2)")
			(pinfunction "R2.1")
			(pintype "passive+no_connect")
		)
		(pad "3" smd roundrect
			(at 0.27 0.45 270)
			(size 0.4 0.5)
			(layers "F.Cu" "F.Paste" "F.Mask")
			(roundrect_rratio 0.25)
			(net 606 "/Peripherals/~{SPI1_CS0_CONN}")
			(pinfunction "R3.1")
			(pintype "passive")
		)
		(pad "4" smd roundrect
			(at 0.8 0.45 270)
			(size 0.4 0.5)
			(layers "F.Cu" "F.Paste" "F.Mask")
			(roundrect_rratio 0.25)
			(net 608 "/Peripherals/~{SPI1_CS1_CONN}")
			(pinfunction "R4.1")
			(pintype "passive")
		)
		(pad "5" smd roundrect
			(at 0.8 -0.452 270)
			(size 0.4 0.5)
			(layers "F.Cu" "F.Paste" "F.Mask")
			(roundrect_rratio 0.25)
			(net 42 "~{SPI1_CS1}")
			(pinfunction "R4.2")
			(pintype "passive")
		)
		(pad "6" smd roundrect
			(at 0.27 -0.452 270)
			(size 0.4 0.5)
			(layers "F.Cu" "F.Paste" "F.Mask")
			(roundrect_rratio 0.25)
			(net 41 "~{SPI1_CS0}")
			(pinfunction "R3.2")
			(pintype "passive")
		)
		(pad "7" smd roundrect
			(at -0.272 -0.452 270)
			(size 0.4 0.5)
			(layers "F.Cu" "F.Paste" "F.Mask")
			(roundrect_rratio 0.25)
			(net 676 "unconnected-(R102-R2.2-Pad7)")
			(pinfunction "R2.2")
			(pintype "passive+no_connect")
		)
		(pad "8" smd roundrect
			(at -0.802 -0.452 270)
			(size 0.4 0.5)
			(layers "F.Cu" "F.Paste" "F.Mask")
			(roundrect_rratio 0.25)
			(net 681 "unconnected-(R102-R1.2-Pad8)")
			(pinfunction "R1.2")
			(pintype "passive+no_connect")
		)
	)
	(footprint "antmicro-footprints:R_0402_1005Metric"
		(layer "F.Cu")
		(at 67.5 119 90)
		(descr "Resistor SMD 0402")
		(tags "resistor SMD 0402")
		(property "Reference" "R104"
			(at -3.65 0.45 90)
			(layer "F.SilkS")
			(effects
				(font
					(size 0.7 0.7)
					(thickness 0.15)
				)
				(justify left bottom)
			)
		)
		(property "Value" "R_2k2_0402"
			(at 0 1.4 90)
			(layer "F.Fab")
			(effects
				(font
					(size 0.7 0.7)
					(thickness 0.15)
				)
				(justify left bottom)
			)
		)
		(property "Footprint" "antmicro-footprints:R_0402_1005Metric"
			(at 0 0 90)
			(layer "F.Fab")
			(hide yes)
			(effects
				(font
					(size 1.27 1.27)
					(thickness 0.15)
				)
			)
		)
		(property "Datasheet" "https://www.bourns.com/docs/product-datasheets/cr.pdf"
			(at 0 0 90)
			(layer "F.Fab")
			(hide yes)
			(effects
				(font
					(size 1.27 1.27)
					(thickness 0.15)
				)
			)
		)
		(property "Author" "Antmicro"
			(at 186.5 51.5 0)
			(layer "F.Fab")
			(hide yes)
			(effects
				(font
					(size 1 1)
					(thickness 0.15)
				)
			)
		)
		(property "License" "Apache-2.0"
			(at 186.5 51.5 0)
			(layer "F.Fab")
			(hide yes)
			(effects
				(font
					(size 1 1)
					(thickness 0.15)
				)
			)
		)
		(property "MPN" "CR0402-FX-2201GLF"
			(at 186.5 51.5 0)
			(layer "F.Fab")
			(hide yes)
			(effects
				(font
					(size 1 1)
					(thickness 0.15)
				)
			)
		)
		(property "Manufacturer" "Bourns"
			(at 186.5 51.5 0)
			(layer "F.Fab")
			(hide yes)
			(effects
				(font
					(size 1 1)
					(thickness 0.15)
				)
			)
		)
		(property "Tolerance" "1%"
			(at 186.5 51.5 0)
			(layer "F.Fab")
			(hide yes)
			(effects
				(font
					(size 1 1)
					(thickness 0.15)
				)
			)
		)
		(property "Val" "2k2"
			(at 186.5 51.5 0)
			(layer "F.Fab")
			(hide yes)
			(effects
				(font
					(size 1 1)
					(thickness 0.15)
				)
			)
		)
		(sheetname "USB Debug, DP")
		(sheetfile "usb.kicad_sch")
		(attr smd)
		(fp_rect
			(start -0.925 -0.47)
			(end 0.925 0.47)
			(stroke
				(width 0.05)
				(type default)
			)
			(fill none)
			(layer "F.CrtYd")
		)
		(fp_rect
			(start -0.5 -0.25)
			(end 0.5 0.25)
			(stroke
				(width 0.15)
				(type solid)
			)
			(fill none)
			(layer "F.Fab")
		)
		(fp_text user "${REFERENCE}"
			(at -0.95 3.168 90)
			(layer "F.Fab")
			(hide yes)
			(effects
				(font
					(size 0.7 0.7)
					(thickness 0.15)
				)
				(justify left bottom)
			)
		)
		(fp_text user "License: Apache-2.0"
			(at -0.95 5.169 90)
			(layer "F.Fab")
			(hide yes)
			(effects
				(font
					(size 0.7 0.7)
					(thickness 0.15)
				)
				(justify left bottom)
			)
		)
		(fp_text user "Author: Antmicro"
			(at -0.95 4.169 90)
			(layer "F.Fab")
			(hide yes)
			(effects
				(font
					(size 0.7 0.7)
					(thickness 0.15)
				)
				(justify left bottom)
			)
		)
		(pad "1" smd roundrect
			(at -0.48 0 90)
			(size 0.59 0.64)
			(layers "F.Cu" "F.Paste" "F.Mask")
			(roundrect_rratio 0.25)
			(net 1 "GND")
			(pintype "passive")
		)
		(pad "2" smd roundrect
			(at 0.48 0 90)
			(size 0.59 0.64)
			(layers "F.Cu" "F.Paste" "F.Mask")
			(roundrect_rratio 0.25)
			(net 682 "Net-(U12-ISET)")
			(pintype "passive")
		)
	)
	(footprint "antmicro-footprints:R_0402_1005Metric"
		(layer "F.Cu")
		(at 89.7 104.6 45)
		(descr "Resistor SMD 0402")
		(tags "resistor SMD 0402")
		(property "Reference" "R214"
			(at -1.909188 -0.636396 45)
			(layer "F.SilkS")
			(effects
				(font
					(size 0.7 0.7)
					(thickness 0.15)
				)
				(justify left bottom)
			)
		)
		(property "Value" "R_499R_0402"
			(at -1.011843 1.772046 45)
			(layer "F.Fab")
			(effects
				(font
					(size 0.7 0.7)
					(thickness 0.15)
				)
				(justify left bottom)
			)
		)
		(property "Footprint" "antmicro-footprints:R_0402_1005Metric"
			(at 0 0 45)
			(layer "F.Fab")
			(hide yes)
			(effects
				(font
					(size 1.27 1.27)
					(thickness 0.15)
				)
			)
		)
		(property "Datasheet" "https://www.mouser.com/datasheet/2/54/cr-1858361.pdf"
			(at 0 0 45)
			(layer "F.Fab")
			(hide yes)
			(effects
				(font
					(size 1.27 1.27)
					(thickness 0.15)
				)
			)
		)
		(property "Author" "Antmicro"
			(at 100.235891 -32.790847 0)
			(layer "F.Fab")
			(hide yes)
			(effects
				(font
					(size 1 1)
					(thickness 0.15)
				)
			)
		)
		(property "License" "Apache-2.0"
			(at 100.235891 -32.790847 0)
			(layer "F.Fab")
			(hide yes)
			(effects
				(font
					(size 1 1)
					(thickness 0.15)
				)
			)
		)
		(property "MPN" "CR0402-FX-4990GLF"
			(at 100.235891 -32.790847 0)
			(layer "F.Fab")
			(hide yes)
			(effects
				(font
					(size 1 1)
					(thickness 0.15)
				)
			)
		)
		(property "Manufacturer" "Bourns"
			(at 100.235891 -32.790847 0)
			(layer "F.Fab")
			(hide yes)
			(effects
				(font
					(size 1 1)
					(thickness 0.15)
				)
			)
		)
		(property "Tolerance" "1%"
			(at 100.235891 -32.790847 0)
			(layer "F.Fab")
			(hide yes)
			(effects
				(font
					(size 1 1)
					(thickness 0.15)
				)
			)
		)
		(property "Val" "499R"
			(at 100.235891 -32.790847 0)
			(layer "F.Fab")
			(hide yes)
			(effects
				(font
					(size 1 1)
					(thickness 0.15)
				)
			)
		)
		(sheetname "HDMI")
		(sheetfile "hdmi.kicad_sch")
		(attr smd)
		(fp_poly
			(pts
				(xy -0.925 -0.47) (xy 0.925 -0.47) (xy 0.925 0.47) (xy -0.925 0.47)
			)
			(stroke
				(width 0.05)
				(type default)
			)
			(fill none)
			(layer "F.CrtYd")
		)
		(fp_poly
			(pts
				(xy -0.5 -0.25) (xy 0.5 -0.25) (xy 0.5 0.25) (xy -0.5 0.25)
			)
			(stroke
				(width 0.15)
				(type solid)
			)
			(fill none)
			(layer "F.Fab")
		)
		(fp_text user "${REFERENCE}"
			(at -0.95 3.168 45)
			(layer "F.Fab")
			(hide yes)
			(effects
				(font
					(size 0.7 0.7)
					(thickness 0.15)
				)
				(justify left bottom)
			)
		)
		(fp_text user "License: Apache-2.0"
			(at -0.949999 5.169 45)
			(layer "F.Fab")
			(hide yes)
			(effects
				(font
					(size 0.7 0.7)
					(thickness 0.15)
				)
				(justify left bottom)
			)
		)
		(fp_text user "Author: Antmicro"
			(at -0.95 4.169 45)
			(layer "F.Fab")
			(hide yes)
			(effects
				(font
					(size 0.7 0.7)
					(thickness 0.15)
				)
				(justify left bottom)
			)
		)
		(pad "1" smd roundrect
			(at -0.48 0 45)
			(size 0.59 0.64)
			(layers "F.Cu" "F.Paste" "F.Mask")
			(roundrect_rratio 0.25)
			(net 623 "Net-(Q2-D)")
			(pintype "passive")
		)
		(pad "2" smd roundrect
			(at 0.48 0 45)
			(size 0.59 0.64)
			(layers "F.Cu" "F.Paste" "F.Mask")
			(roundrect_rratio 0.25)
			(net 488 "/HDMI/HDMI_D0_N")
			(pintype "passive")
		)
	)
	(footprint "antmicro-footprints:R_0402_1005Metric"
		(layer "F.Cu")
		(at 128.9 107.9 -90)
		(descr "Resistor SMD 0402")
		(tags "resistor SMD 0402")
		(property "Reference" "R187"
			(at 3.85 -0.37 -90)
			(layer "F.SilkS")
			(effects
				(font
					(size 0.7 0.7)
					(thickness 0.15)
				)
				(justify left bottom)
			)
		)
		(property "Value" "R_200R_0402"
			(at 0 1.4 -90)
			(layer "F.Fab")
			(effects
				(font
					(size 0.7 0.7)
					(thickness 0.15)
				)
				(justify left bottom)
			)
		)
		(property "Footprint" "antmicro-footprints:R_0402_1005Metric"
			(at 0 0 -90)
			(layer "F.Fab")
			(hide yes)
			(effects
				(font
					(size 1.27 1.27)
					(thickness 0.15)
				)
			)
		)
		(property "Datasheet" "https://www.bourns.com/docs/product-datasheets/cr.pdf"
			(at 0 0 -90)
			(layer "F.Fab")
			(hide yes)
			(effects
				(font
					(size 1.27 1.27)
					(thickness 0.15)
				)
			)
		)
		(property "Author" "Antmicro"
			(at 21 236.8 0)
			(layer "F.Fab")
			(hide yes)
			(effects
				(font
					(size 1 1)
					(thickness 0.15)
				)
			)
		)
		(property "License" "Apache-2.0"
			(at 21 236.8 0)
			(layer "F.Fab")
			(hide yes)
			(effects
				(font
					(size 1 1)
					(thickness 0.15)
				)
			)
		)
		(property "MPN" "CR0402-FX-2000GLF"
			(at 21 236.8 0)
			(layer "F.Fab")
			(hide yes)
			(effects
				(font
					(size 1 1)
					(thickness 0.15)
				)
			)
		)
		(property "Manufacturer" "Bourns"
			(at 21 236.8 0)
			(layer "F.Fab")
			(hide yes)
			(effects
				(font
					(size 1 1)
					(thickness 0.15)
				)
			)
		)
		(property "Tolerance" "1%"
			(at 21 236.8 0)
			(layer "F.Fab")
			(hide yes)
			(effects
				(font
					(size 1 1)
					(thickness 0.15)
				)
			)
		)
		(property "Val" "200R"
			(at 21 236.8 0)
			(layer "F.Fab")
			(hide yes)
			(effects
				(font
					(size 1 1)
					(thickness 0.15)
				)
			)
		)
		(sheetname "M.2")
		(sheetfile "m-2.kicad_sch")
		(attr smd)
		(fp_rect
			(start -0.925 -0.47)
			(end 0.925 0.47)
			(stroke
				(width 0.05)
				(type default)
			)
			(fill none)
			(layer "F.CrtYd")
		)
		(fp_rect
			(start -0.5 -0.25)
			(end 0.5 0.25)
			(stroke
				(width 0.15)
				(type solid)
			)
			(fill none)
			(layer "F.Fab")
		)
		(fp_text user "License: Apache-2.0"
			(at -0.95 5.169 -90)
			(layer "F.Fab")
			(hide yes)
			(effects
				(font
					(size 0.7 0.7)
					(thickness 0.15)
				)
				(justify left bottom)
			)
		)
		(fp_text user "Author: Antmicro"
			(at -0.95 4.169 -90)
			(layer "F.Fab")
			(hide yes)
			(effects
				(font
					(size 0.7 0.7)
					(thickness 0.15)
				)
				(justify left bottom)
			)
		)
		(fp_text user "${REFERENCE}"
			(at -0.95 3.168 -90)
			(layer "F.Fab")
			(hide yes)
			(effects
				(font
					(size 0.7 0.7)
					(thickness 0.15)
				)
				(justify left bottom)
			)
		)
		(pad "1" smd roundrect
			(at -0.48 0 270)
			(size 0.59 0.64)
			(layers "F.Cu" "F.Paste" "F.Mask")
			(roundrect_rratio 0.25)
			(net 653 "Net-(D52-A)")
			(pintype "passive")
		)
		(pad "2" smd roundrect
			(at 0.48 0 270)
			(size 0.59 0.64)
			(layers "F.Cu" "F.Paste" "F.Mask")
			(roundrect_rratio 0.25)
			(net 87 "+3V3")
			(pintype "passive")
		)
	)
	(footprint "antmicro-footprints:R_0402_1005Metric"
		(layer "F.Cu")
		(at 127.05 98.6 180)
		(descr "Resistor SMD 0402")
		(tags "resistor SMD 0402")
		(property "Reference" "R28"
			(at 1.05 0.45 180)
			(layer "F.SilkS")
			(effects
				(font
					(size 0.7 0.7)
					(thickness 0.15)
				)
				(justify left bottom)
			)
		)
		(property "Value" "R_47k_0402"
			(at 0 1.4 180)
			(layer "F.Fab")
			(effects
				(font
					(size 0.7 0.7)
					(thickness 0.15)
				)
				(justify left bottom)
			)
		)
		(property "Footprint" "antmicro-footprints:R_0402_1005Metric"
			(at 0 0 180)
			(layer "F.Fab")
			(hide yes)
			(effects
				(font
					(size 1.27 1.27)
					(thickness 0.15)
				)
			)
		)
		(property "Datasheet" "https://www.bourns.com/docs/product-datasheets/cr.pdf"
			(at 0 0 180)
			(layer "F.Fab")
			(hide yes)
			(effects
				(font
					(size 1.27 1.27)
					(thickness 0.15)
				)
			)
		)
		(property "Author" "Antmicro"
			(at 254.1 197.2 0)
			(layer "F.Fab")
			(hide yes)
			(effects
				(font
					(size 1 1)
					(thickness 0.15)
				)
			)
		)
		(property "License" "Apache-2.0"
			(at 254.1 197.2 0)
			(layer "F.Fab")
			(hide yes)
			(effects
				(font
					(size 1 1)
					(thickness 0.15)
				)
			)
		)
		(property "MPN" "CR0402-FX-4702GLF"
			(at 254.1 197.2 0)
			(layer "F.Fab")
			(hide yes)
			(effects
				(font
					(size 1 1)
					(thickness 0.15)
				)
			)
		)
		(property "Manufacturer" "Bourns"
			(at 254.1 197.2 0)
			(layer "F.Fab")
			(hide yes)
			(effects
				(font
					(size 1 1)
					(thickness 0.15)
				)
			)
		)
		(property "Tolerance" "1%"
			(at 254.1 197.2 0)
			(layer "F.Fab")
			(hide yes)
			(effects
				(font
					(size 1 1)
					(thickness 0.15)
				)
			)
		)
		(property "Val" "47k"
			(at 254.1 197.2 0)
			(layer "F.Fab")
			(hide yes)
			(effects
				(font
					(size 1 1)
					(thickness 0.15)
				)
			)
		)
		(sheetname "M.2")
		(sheetfile "m-2.kicad_sch")
		(attr smd exclude_from_pos_files exclude_from_bom dnp)
		(fp_rect
			(start -0.925 -0.47)
			(end 0.925 0.47)
			(stroke
				(width 0.05)
				(type default)
			)
			(fill none)
			(layer "F.CrtYd")
		)
		(fp_rect
			(start -0.5 -0.25)
			(end 0.5 0.25)
			(stroke
				(width 0.15)
				(type solid)
			)
			(fill none)
			(layer "F.Fab")
		)
		(fp_text user "License: Apache-2.0"
			(at -0.95 5.169 180)
			(layer "F.Fab")
			(hide yes)
			(effects
				(font
					(size 0.7 0.7)
					(thickness 0.15)
				)
				(justify left bottom)
			)
		)
		(fp_text user "Author: Antmicro"
			(at -0.95 4.169 180)
			(layer "F.Fab")
			(hide yes)
			(effects
				(font
					(size 0.7 0.7)
					(thickness 0.15)
				)
				(justify left bottom)
			)
		)
		(fp_text user "${REFERENCE}"
			(at -0.95 3.168 180)
			(layer "F.Fab")
			(hide yes)
			(effects
				(font
					(size 0.7 0.7)
					(thickness 0.15)
				)
				(justify left bottom)
			)
		)
		(pad "1" smd roundrect
			(at -0.48 0 180)
			(size 0.59 0.64)
			(layers "F.Cu" "F.Paste" "F.Mask")
			(roundrect_rratio 0.25)
			(net 87 "+3V3")
			(pintype "passive")
		)
		(pad "2" smd roundrect
			(at 0.48 0 180)
			(size 0.59 0.64)
			(layers "F.Cu" "F.Paste" "F.Mask")
			(roundrect_rratio 0.25)
			(net 64 "PCIE1_CLKREQ*")
			(pintype "passive")
		)
	)
)
